(kicad_pcb
	(version 20241229)
	(generator "pcbnew")
	(generator_version "9.0")
	(general
		(thickness 1.62)
		(legacy_teardrops no)
	)
	(paper "A3")
	(title_block
		(title "COM Express 7 Baseboard")
		(date "2025-02-04")
		(rev "1.1.2")
		(company "Antmicro Ltd")
		(comment 1 "www.antmicro.com")
		(comment 9 "footprints 429-433 of 802")
	)
	(layers
		(0 "F.Cu" signal)
		(4 "In1.Cu" signal)
		(6 "In2.Cu" signal)
		(8 "In3.Cu" signal)
		(10 "In4.Cu" signal)
		(12 "In5.Cu" signal)
		(14 "In6.Cu" signal)
		(2 "B.Cu" signal)
		(9 "F.Adhes" user "F.Adhesive")
		(11 "B.Adhes" user "B.Adhesive")
		(13 "F.Paste" user)
		(15 "B.Paste" user)
		(5 "F.SilkS" user "F.Silkscreen")
		(7 "B.SilkS" user "B.Silkscreen")
		(1 "F.Mask" user)
		(3 "B.Mask" user)
		(17 "Dwgs.User" user "User.Drawings")
		(19 "Cmts.User" user "User.Comments")
		(21 "Eco1.User" user "User.Eco1")
		(23 "Eco2.User" user "User.Eco2")
		(25 "Edge.Cuts" user)
		(27 "Margin" user)
		(31 "F.CrtYd" user "F.Courtyard")
		(29 "B.CrtYd" user "B.Courtyard")
		(35 "F.Fab" user)
		(33 "B.Fab" user)
	)
	(footprint "antmicro-footprints:R_0201"
		(layer "F.Cu")
		(at 150.33 147.336 -90)
		(descr "Resistor SMD 0201")
		(tags "resistor SMD 0201")
		(property "Reference" "R275"
			(at 4.099 -0.57 270)
			(layer "F.SilkS")
			(effects
				(font
					(size 0.7 0.7)
					(thickness 0.15)
				)
				(justify left bottom)
			)
		)
		(property "Value" "R_0R_0201"
			(at 0 1.25 270)
			(layer "F.Fab")
			(effects
				(font
					(size 0.7 0.7)
					(thickness 0.15)
				)
				(justify left bottom)
			)
		)
		(property "Datasheet" "https://www.bourns.com/docs/product-datasheets/cr.pdf"
			(at 0 0 270)
			(layer "F.Fab")
			(hide yes)
			(effects
				(font
					(size 1.27 1.27)
					(thickness 0.15)
				)
			)
		)
		(property "Author" "Antmicro"
			(at 2.994 297.666 0)
			(layer "F.Fab")
			(hide yes)
			(effects
				(font
					(size 1 1)
					(thickness 0.15)
				)
			)
		)
		(property "License" "Apache-2.0"
			(at 2.994 297.666 0)
			(layer "F.Fab")
			(hide yes)
			(effects
				(font
					(size 1 1)
					(thickness 0.15)
				)
			)
		)
		(property "MPN" "CR0201-FX-0R00GLF"
			(at 2.994 297.666 0)
			(layer "F.Fab")
			(hide yes)
			(effects
				(font
					(size 1 1)
					(thickness 0.15)
				)
			)
		)
		(property "Manufacturer" "Bourns"
			(at 2.994 297.666 0)
			(layer "F.Fab")
			(hide yes)
			(effects
				(font
					(size 1 1)
					(thickness 0.15)
				)
			)
		)
		(property "Tolerance" "1%"
			(at 2.994 297.666 0)
			(layer "F.Fab")
			(hide yes)
			(effects
				(font
					(size 1 1)
					(thickness 0.15)
				)
			)
		)
		(property "Val" "0R"
			(at 2.994 297.666 0)
			(layer "F.Fab")
			(hide yes)
			(effects
				(font
					(size 1 1)
					(thickness 0.15)
				)
			)
		)
		(sheetname "KR to SFI #1")
		(sheetfile "kr_sfi.kicad_sch")
		(attr smd)
		(fp_rect
			(start -0.7 -0.35)
			(end 0.7 0.35)
			(stroke
				(width 0.05)
				(type default)
			)
			(fill no)
			(layer "F.CrtYd")
		)
		(fp_rect
			(start -0.3 -0.15)
			(end 0.298 0.148)
			(stroke
				(width 0.15)
				(type solid)
			)
			(fill no)
			(layer "F.Fab")
		)
		(pad "" smd roundrect
			(at -0.346 0 270)
			(size 0.318 0.36)
			(layers "F.Paste")
			(roundrect_rratio 0.25)
			(teardrops
				(best_length_ratio 0.2)
				(max_length 1)
				(best_width_ratio 0.9)
				(max_width 2)
				(curved_edges yes)
				(filter_ratio 0.9)
				(enabled yes)
				(allow_two_segments yes)
				(prefer_zone_connections yes)
			)
		)
		(pad "" smd roundrect
			(at 0.344 0 270)
			(size 0.318 0.36)
			(layers "F.Paste")
			(roundrect_rratio 0.25)
			(teardrops
				(best_length_ratio 0.2)
				(max_length 1)
				(best_width_ratio 0.9)
				(max_width 2)
				(curved_edges yes)
				(filter_ratio 0.9)
				(enabled yes)
				(allow_two_segments yes)
				(prefer_zone_connections yes)
			)
		)
		(pad "1" smd roundrect
			(at -0.32 0 270)
			(size 0.46 0.4)
			(layers "F.Cu" "F.Mask")
			(roundrect_rratio 0.25)
			(net 686 "/2xSFP+/KR to SFI #1/SFI_R.RX-")
			(pintype "passive")
			(teardrops
				(best_length_ratio 0.2)
				(max_length 1)
				(best_width_ratio 0.9)
				(max_width 2)
				(curved_edges yes)
				(filter_ratio 0.9)
				(enabled yes)
				(allow_two_segments yes)
				(prefer_zone_connections yes)
			)
		)
		(pad "2" smd roundrect
			(at 0.32 0 270)
			(size 0.46 0.4)
			(layers "F.Cu" "F.Mask")
			(roundrect_rratio 0.25)
			(net 170 "/2xSFP+/SFI0.RX-")
			(pintype "passive")
			(teardrops
				(best_length_ratio 0.2)
				(max_length 1)
				(best_width_ratio 0.9)
				(max_width 2)
				(curved_edges yes)
				(filter_ratio 0.9)
				(enabled yes)
				(allow_two_segments yes)
				(prefer_zone_connections yes)
			)
		)
	)
	(footprint "antmicro-footprints:L_WE-MAPI-4020"
		(layer "F.Cu")
		(at 311.215499 91.4365 180)
		(property "Reference" "L3"
			(at -2.234501 1.3765 0)
			(layer "F.SilkS")
			(effects
				(font
					(size 0.7 0.7)
					(thickness 0.15)
				)
				(justify left bottom)
			)
		)
		(property "Value" "L_1u8_6.8A_WE-MAPI-4020"
			(at -2.4 3.4 0)
			(layer "F.Fab")
			(effects
				(font
					(size 0.7 0.7)
					(thickness 0.15)
				)
				(justify left bottom)
			)
		)
		(property "Datasheet" "https://www.we-online.com/components/products/datasheet/74438356018.pdf"
			(at 0 0 180)
			(layer "F.Fab")
			(hide yes)
			(effects
				(font
					(size 1.27 1.27)
					(thickness 0.15)
				)
			)
		)
		(property "Author" "Antmicro"
			(at 622.430998 182.873 0)
			(layer "F.Fab")
			(hide yes)
			(effects
				(font
					(size 1 1)
					(thickness 0.15)
				)
			)
		)
		(property "IMax" "6.8 A"
			(at 622.430998 182.873 0)
			(layer "F.Fab")
			(hide yes)
			(effects
				(font
					(size 1 1)
					(thickness 0.15)
				)
			)
		)
		(property "ISat" "6.5 A"
			(at 622.430998 182.873 0)
			(layer "F.Fab")
			(hide yes)
			(effects
				(font
					(size 1 1)
					(thickness 0.15)
				)
			)
		)
		(property "License" "Apache-2.0"
			(at 622.430998 182.873 0)
			(layer "F.Fab")
			(hide yes)
			(effects
				(font
					(size 1 1)
					(thickness 0.15)
				)
			)
		)
		(property "MPN" "74438356018"
			(at 622.430998 182.873 0)
			(layer "F.Fab")
			(hide yes)
			(effects
				(font
					(size 1 1)
					(thickness 0.15)
				)
			)
		)
		(property "Manufacturer" "Würth Elektronik"
			(at 622.430998 182.873 0)
			(layer "F.Fab")
			(hide yes)
			(effects
				(font
					(size 1 1)
					(thickness 0.15)
				)
			)
		)
		(property "Public" "False"
			(at 622.430998 182.873 0)
			(layer "F.Fab")
			(hide yes)
			(effects
				(font
					(size 1 1)
					(thickness 0.15)
				)
			)
		)
		(property "Size" "4.1x4.1mm"
			(at 622.430998 182.873 0)
			(layer "F.Fab")
			(hide yes)
			(effects
				(font
					(size 1 1)
					(thickness 0.15)
				)
			)
		)
		(property "Val" "1u8/6.8A"
			(at 622.430998 182.873 0)
			(layer "F.Fab")
			(hide yes)
			(effects
				(font
					(size 1 1)
					(thickness 0.15)
				)
			)
		)
		(sheetname "Power")
		(sheetfile "power.kicad_sch")
		(attr smd)
		(fp_rect
			(start -2.2 -2.2)
			(end 2.2 2.2)
			(stroke
				(width 0.15)
				(type solid)
			)
			(fill no)
			(layer "F.SilkS")
		)
		(fp_rect
			(start -2.3 -2.3)
			(end 2.3 2.3)
			(stroke
				(width 0.05)
				(type solid)
			)
			(fill no)
			(layer "F.CrtYd")
		)
		(fp_rect
			(start -2.05 -2.05)
			(end 2.05 2.05)
			(stroke
				(width 0.15)
				(type solid)
			)
			(fill no)
			(layer "F.Fab")
		)
		(pad "1" smd roundrect
			(at -1.185 0 270)
			(size 3.7 1)
			(layers "F.Cu" "F.Mask" "F.Paste")
			(roundrect_rratio 0.1)
			(net 870 "Net-(U21-SW)")
			(pintype "passive")
			(teardrops
				(best_length_ratio 0.2)
				(max_length 1)
				(best_width_ratio 0.9)
				(max_width 2)
				(curved_edges yes)
				(filter_ratio 0.9)
				(enabled yes)
				(allow_two_segments yes)
				(prefer_zone_connections yes)
			)
		)
		(pad "2" smd roundrect
			(at 1.185 0 270)
			(size 3.7 1)
			(layers "F.Cu" "F.Mask" "F.Paste")
			(roundrect_rratio 0.1)
			(net 75 "Net-(U50-IN+)")
			(pintype "passive")
			(teardrops
				(best_length_ratio 0.2)
				(max_length 1)
				(best_width_ratio 0.9)
				(max_width 2)
				(curved_edges yes)
				(filter_ratio 0.9)
				(enabled yes)
				(allow_two_segments yes)
				(prefer_zone_connections yes)
			)
		)
	)
	(footprint "antmicro-footprints:R_0402_1005Metric"
		(layer "F.Cu")
		(at 310.1 74.81 180)
		(descr "Resistor SMD 0402")
		(tags "resistor SMD 0402")
		(property "Reference" "R165"
			(at 0.8 -0.45 0)
			(layer "F.SilkS")
			(effects
				(font
					(size 0.7 0.7)
					(thickness 0.15)
				)
				(justify right bottom)
			)
		)
		(property "Value" "R_2k2_0402"
			(at -1.011843 1.772047 0)
			(layer "F.Fab")
			(effects
				(font
					(size 0.7 0.7)
					(thickness 0.15)
				)
				(justify right bottom)
			)
		)
		(property "Datasheet" "https://www.bourns.com/docs/product-datasheets/cr.pdf"
			(at 0 0 180)
			(layer "F.Fab")
			(hide yes)
			(effects
				(font
					(size 1.27 1.27)
					(thickness 0.15)
				)
			)
		)
		(property "Author" "Antmicro"
			(at 620.2 149.62 0)
			(layer "F.Fab")
			(hide yes)
			(effects
				(font
					(size 1 1)
					(thickness 0.15)
				)
			)
		)
		(property "License" "Apache-2.0"
			(at 620.2 149.62 0)
			(layer "F.Fab")
			(hide yes)
			(effects
				(font
					(size 1 1)
					(thickness 0.15)
				)
			)
		)
		(property "MPN" "CR0402-FX-2201GLF"
			(at 620.2 149.62 0)
			(layer "F.Fab")
			(hide yes)
			(effects
				(font
					(size 1 1)
					(thickness 0.15)
				)
			)
		)
		(property "Manufacturer" "Bourns"
			(at 620.2 149.62 0)
			(layer "F.Fab")
			(hide yes)
			(effects
				(font
					(size 1 1)
					(thickness 0.15)
				)
			)
		)
		(property "Public" "False"
			(at 620.2 149.62 0)
			(layer "F.Fab")
			(hide yes)
			(effects
				(font
					(size 1 1)
					(thickness 0.15)
				)
			)
		)
		(property "Tolerance" "1%"
			(at 620.2 149.62 0)
			(layer "F.Fab")
			(hide yes)
			(effects
				(font
					(size 1 1)
					(thickness 0.15)
				)
			)
		)
		(property "Val" "2k2"
			(at 620.2 149.62 0)
			(layer "F.Fab")
			(hide yes)
			(effects
				(font
					(size 1 1)
					(thickness 0.15)
				)
			)
		)
		(sheetname "Com Express 7 MGMT")
		(sheetfile "com_express_7_mgmt.kicad_sch")
		(attr smd)
		(fp_rect
			(start -0.925 -0.47)
			(end 0.925 0.47)
			(stroke
				(width 0.05)
				(type default)
			)
			(fill no)
			(layer "F.CrtYd")
		)
		(fp_rect
			(start -0.5 -0.25)
			(end 0.5 0.25)
			(stroke
				(width 0.15)
				(type solid)
			)
			(fill no)
			(layer "F.Fab")
		)
		(pad "1" smd roundrect
			(at -0.48 0 180)
			(size 0.59 0.64)
			(layers "F.Cu" "F.Mask" "F.Paste")
			(roundrect_rratio 0.25)
			(net 41 "Net-(BT1-+)")
			(pintype "passive")
			(teardrops
				(best_length_ratio 0.2)
				(max_length 1)
				(best_width_ratio 0.9)
				(max_width 2)
				(curved_edges yes)
				(filter_ratio 0.9)
				(enabled yes)
				(allow_two_segments yes)
				(prefer_zone_connections yes)
			)
		)
		(pad "2" smd roundrect
			(at 0.48 0 180)
			(size 0.59 0.64)
			(layers "F.Cu" "F.Mask" "F.Paste")
			(roundrect_rratio 0.25)
			(net 135 "Net-(D19-Pad3)")
			(pintype "passive")
			(teardrops
				(best_length_ratio 0.2)
				(max_length 1)
				(best_width_ratio 0.9)
				(max_width 2)
				(curved_edges yes)
				(filter_ratio 0.9)
				(enabled yes)
				(allow_two_segments yes)
				(prefer_zone_connections yes)
			)
		)
	)
	(footprint "antmicro-footprints:C_0603_1608Metric"
		(layer "F.Cu")
		(at 314.2505 95.1365 90)
		(descr "Capacitor SMD 0603")
		(tags "capacitor 0603")
		(property "Reference" "C59"
			(at 1.1765 0.5995 90)
			(layer "F.SilkS")
			(effects
				(font
					(size 0.7 0.7)
					(thickness 0.15)
				)
				(justify left bottom)
			)
		)
		(property "Value" "C_22u_16V_0603"
			(at -1.42757 1.770288 90)
			(layer "F.Fab")
			(effects
				(font
					(size 0.7 0.7)
					(thickness 0.15)
				)
				(justify left bottom)
			)
		)
		(property "Datasheet" "https://product.samsungsem.com/mlcc/CL10A226MO7JZN.do"
			(at 0 0 90)
			(layer "F.Fab")
			(hide yes)
			(effects
				(font
					(size 1.27 1.27)
					(thickness 0.15)
				)
			)
		)
		(property "Author" "Antmicro"
			(at 409.387 -219.114 0)
			(layer "F.Fab")
			(hide yes)
			(effects
				(font
					(size 1 1)
					(thickness 0.15)
				)
			)
		)
		(property "Dielectric" ""
			(at 409.387 -219.114 0)
			(layer "F.Fab")
			(hide yes)
			(effects
				(font
					(size 1 1)
					(thickness 0.15)
				)
			)
		)
		(property "License" "Apache-2.0"
			(at 409.387 -219.114 0)
			(layer "F.Fab")
			(hide yes)
			(effects
				(font
					(size 1 1)
					(thickness 0.15)
				)
			)
		)
		(property "MPN" "CL10A226MO7JZNC"
			(at 409.387 -219.114 0)
			(layer "F.Fab")
			(hide yes)
			(effects
				(font
					(size 1 1)
					(thickness 0.15)
				)
			)
		)
		(property "Manufacturer" "Samsung Electro-Mechanics"
			(at 409.387 -219.114 0)
			(layer "F.Fab")
			(hide yes)
			(effects
				(font
					(size 1 1)
					(thickness 0.15)
				)
			)
		)
		(property "Public" "False"
			(at 409.387 -219.114 0)
			(layer "F.Fab")
			(hide yes)
			(effects
				(font
					(size 1 1)
					(thickness 0.15)
				)
			)
		)
		(property "Val" "22u"
			(at 409.387 -219.114 0)
			(layer "F.Fab")
			(hide yes)
			(effects
				(font
					(size 1 1)
					(thickness 0.15)
				)
			)
		)
		(property "Voltage" "16V"
			(at 409.387 -219.114 0)
			(layer "F.Fab")
			(hide yes)
			(effects
				(font
					(size 1 1)
					(thickness 0.15)
				)
			)
		)
		(sheetname "Power")
		(sheetfile "power.kicad_sch")
		(attr smd)
		(fp_line
			(start -0.15 -0.4)
			(end 0.15 -0.4)
			(stroke
				(width 0.15)
				(type solid)
			)
			(layer "F.SilkS")
		)
		(fp_line
			(start -0.15 0.4)
			(end 0.15 0.4)
			(stroke
				(width 0.15)
				(type solid)
			)
			(layer "F.SilkS")
		)
		(fp_rect
			(start -1.25 -0.65)
			(end 1.25 0.65)
			(stroke
				(width 0.05)
				(type solid)
			)
			(fill no)
			(layer "F.CrtYd")
		)
		(fp_rect
			(start -0.8 -0.4)
			(end 0.8 0.4)
			(stroke
				(width 0.15)
				(type solid)
			)
			(fill no)
			(layer "F.Fab")
		)
		(pad "1" smd roundrect
			(at -0.7 0 90)
			(size 0.8 1)
			(layers "F.Cu" "F.Mask" "F.Paste")
			(roundrect_rratio 0.2)
			(net 1 "GND")
			(pintype "passive")
			(teardrops
				(best_length_ratio 0.2)
				(max_length 1)
				(best_width_ratio 0.9)
				(max_width 2)
				(curved_edges yes)
				(filter_ratio 0.9)
				(enabled yes)
				(allow_two_segments yes)
				(prefer_zone_connections yes)
			)
		)
		(pad "2" smd roundrect
			(at 0.7 0 90)
			(size 0.8 1)
			(layers "F.Cu" "F.Mask" "F.Paste")
			(roundrect_rratio 0.2)
			(net 62 "+12V_AON")
			(pintype "passive")
			(teardrops
				(best_length_ratio 0.2)
				(max_length 1)
				(best_width_ratio 0.9)
				(max_width 2)
				(curved_edges yes)
				(filter_ratio 0.9)
				(enabled yes)
				(allow_two_segments yes)
				(prefer_zone_connections yes)
			)
		)
	)
	(footprint "antmicro-footprints:F_1206_3216Metric"
		(layer "F.Cu")
		(at 310.85 149.11 90)
		(property "Reference" "F1"
			(at -0.7 2.1 90)
			(layer "F.SilkS")
			(effects
				(font
					(size 0.7 0.7)
					(thickness 0.15)
				)
				(justify left bottom)
			)
		)
		(property "Value" "F_12A_1206"
			(at -3.6 1.57 90)
			(layer "F.Fab")
			(effects
				(font
					(size 0.7 0.7)
					(thickness 0.15)
				)
				(justify right bottom mirror)
			)
		)
		(property "Datasheet" "https://us.schurter.com/pdf/english/typ_UST_1206.pdf"
			(at 0 0 90)
			(layer "F.Fab")
			(hide yes)
			(effects
				(font
					(size 1.27 1.27)
					(thickness 0.15)
				)
			)
		)
		(property "Author" "Antmicro"
			(at 459.96 -161.74 0)
			(layer "F.Fab")
			(hide yes)
			(effects
				(font
					(size 1 1)
					(thickness 0.15)
				)
			)
		)
		(property "License" "Apache-2.0"
			(at 459.96 -161.74 0)
			(layer "F.Fab")
			(hide yes)
			(effects
				(font
					(size 1 1)
					(thickness 0.15)
				)
			)
		)
		(property "MPN" "3413.0329.22"
			(at 459.96 -161.74 0)
			(layer "F.Fab")
			(hide yes)
			(effects
				(font
					(size 1 1)
					(thickness 0.15)
				)
			)
		)
		(property "Manufacturer" "Schurter"
			(at 459.96 -161.74 0)
			(layer "F.Fab")
			(hide yes)
			(effects
				(font
					(size 1 1)
					(thickness 0.15)
				)
			)
		)
		(sheetname "Power")
		(sheetfile "power.kicad_sch")
		(attr smd)
		(fp_line
			(start 0.8 -0.899)
			(end -0.8 -0.899)
			(stroke
				(width 0.15)
				(type solid)
			)
			(layer "F.SilkS")
		)
		(fp_line
			(start 0.8 0.901)
			(end -0.8 0.901)
			(stroke
				(width 0.15)
				(type solid)
			)
			(layer "F.SilkS")
		)
		(fp_rect
			(start -2.325 -1.15)
			(end 2.325 1.15)
			(stroke
				(width 0.05)
				(type default)
			)
			(fill no)
			(layer "F.CrtYd")
		)
		(fp_line
			(start 1.624 -0.861)
			(end 1.624 0.792)
			(stroke
				(width 0.15)
				(type solid)
			)
			(layer "F.Fab")
		)
		(fp_line
			(start -1.677 -0.861)
			(end 1.624 -0.861)
			(stroke
				(width 0.15)
				(type solid)
			)
			(layer "F.Fab")
		)
		(fp_line
			(start 1.624 0.792)
			(end -1.677 0.792)
			(stroke
				(width 0.15)
				(type solid)
			)
			(layer "F.Fab")
		)
		(fp_line
			(start -1.677 0.792)
			(end -1.677 -0.861)
			(stroke
				(width 0.15)
				(type solid)
			)
			(layer "F.Fab")
		)
		(pad "1" smd roundrect
			(at -1.5 0.001 90)
			(size 1.15 1.8)
			(layers "F.Cu" "F.Mask" "F.Paste")
			(roundrect_rratio 0.25)
			(net 144 "VCC")
			(pintype "passive")
			(teardrops
				(best_length_ratio 0.2)
				(max_length 1)
				(best_width_ratio 0.9)
				(max_width 2)
				(curved_edges yes)
				(filter_ratio 0.9)
				(enabled yes)
				(allow_two_segments yes)
				(prefer_zone_connections yes)
			)
		)
		(pad "2" smd roundrect
			(at 1.5 0.001 90)
			(size 1.15 1.8)
			(layers "F.Cu" "F.Mask" "F.Paste")
			(roundrect_rratio 0.25)
			(net 145 "Net-(D24-C)")
			(pintype "passive")
			(teardrops
				(best_length_ratio 0.2)
				(max_length 1)
				(best_width_ratio 0.9)
				(max_width 2)
				(curved_edges yes)
				(filter_ratio 0.9)
				(enabled yes)
				(allow_two_segments yes)
				(prefer_zone_connections yes)
			)
		)
	)
)
